(kicad_pcb
	(version 20260206)
	(generator "pcbnew")
	(generator_version "10.0")
	(general
		(thickness 1.6)
		(legacy_teardrops no)
	)
	(paper "A4")
	(title_block
		(title "9052_F0T_PDB_Converter_Brick_F_V03_1208_1600_OCP.brd")
		(comment 1 "Grand Teton / footprints 351-355 of 578")
	)
	(layers
		(0 "F.Cu" signal "TOP")
		(4 "In1.Cu" signal "GND")
		(6 "In2.Cu" signal "IN1")
		(8 "In3.Cu" signal "GND1")
		(10 "In4.Cu" signal "VCC")
		(12 "In5.Cu" signal "VCC1")
		(14 "In6.Cu" signal "GND2")
		(16 "In7.Cu" signal "IN2")
		(18 "In8.Cu" signal "GND3")
		(2 "B.Cu" signal "BOTTOM")
		(9 "F.Adhes" user "F.Adhesive")
		(11 "B.Adhes" user "B.Adhesive")
		(13 "F.Paste" user "Package Geometry/Pastemask Top")
		(15 "B.Paste" user "Package Geometry/Pastemask Bottom")
		(5 "F.SilkS" user "Ref Des/Silkscreen Top")
		(7 "B.SilkS" user "Ref Des/Silkscreen Bottom")
		(1 "F.Mask" user "Board Geometry/Soldermask Top")
		(3 "B.Mask" user "Board Geometry/Soldermask Bottom")
		(17 "Dwgs.User" user "User.Drawings")
		(19 "Cmts.User" user "User.Comments")
		(21 "Eco1.User" user "User.Eco1")
		(23 "Eco2.User" user "User.Eco2")
		(25 "Edge.Cuts" user "Board Geometry/Outline")
		(27 "Margin" user)
		(31 "F.CrtYd" user "Package Geometry/Place Bound Top")
		(29 "B.CrtYd" user "Package Geometry/Place Bound Bottom")
		(35 "F.Fab" user "Ref Des/Assembly Top")
		(33 "B.Fab" user "Ref Des/Assembly Bottom")
	)
	(footprint ""
		(layer "B.Cu")
		(at 275.931122 -104.506522 -90)
		(property "Reference" "PD15"
			(at -0.522478 1.510792 270)
			(unlocked yes)
			(layer "B.SilkS")
			(effects
				(font
					(size 0.7874 0.5842)
					(thickness 0.1524)
				)
				(justify left mirror)
			)
		)
		(property "Value" ""
			(at 0 0 90)
			(layer "B.Fab")
			(effects
				(font
					(size 1.27 1.27)
				)
				(justify mirror)
			)
		)
		(duplicate_pad_numbers_are_jumpers no)
		(fp_line
			(start -2.032 0.7112)
			(end 1.651 0.7112)
			(stroke
				(width 0.1524)
				(type default)
			)
			(layer "B.SilkS")
		)
		(fp_line
			(start 1.651 0.7112)
			(end 1.651 -0.7112)
			(stroke
				(width 0.1524)
				(type default)
			)
			(layer "B.SilkS")
		)
		(fp_line
			(start -1.778 0.6858)
			(end -1.778 -0.6858)
			(stroke
				(width 0.1524)
				(type default)
			)
			(layer "B.SilkS")
		)
		(fp_line
			(start 0.299974 0.500126)
			(end -0.199898 0)
			(stroke
				(width 0.1524)
				(type default)
			)
			(layer "B.SilkS")
		)
		(fp_line
			(start -0.199898 0)
			(end 0.299974 -0.500126)
			(stroke
				(width 0.1524)
				(type default)
			)
			(layer "B.SilkS")
		)
		(fp_line
			(start -0.299974 -0.500126)
			(end -0.299974 0.500126)
			(stroke
				(width 0.1524)
				(type default)
			)
			(layer "B.SilkS")
		)
		(fp_line
			(start 0.299974 -0.500126)
			(end 0.299974 0.500126)
			(stroke
				(width 0.1524)
				(type default)
			)
			(layer "B.SilkS")
		)
		(fp_line
			(start -1.905 -0.6858)
			(end -1.905 0.6858)
			(stroke
				(width 0.1524)
				(type default)
			)
			(layer "B.SilkS")
		)
		(fp_line
			(start -1.651 -0.6858)
			(end -1.651 0.6858)
			(stroke
				(width 0.1524)
				(type default)
			)
			(layer "B.SilkS")
		)
		(fp_line
			(start -2.032 -0.7112)
			(end -2.032 0.7112)
			(stroke
				(width 0.1524)
				(type default)
			)
			(layer "B.SilkS")
		)
		(fp_line
			(start 1.651 -0.7112)
			(end -2.032 -0.7112)
			(stroke
				(width 0.1524)
				(type default)
			)
			(layer "B.SilkS")
		)
		(fp_line
			(start -0.899922 0.700024)
			(end 0.899922 0.700024)
			(stroke
				(width 0.1)
				(type default)
			)
			(layer "B.Fab")
		)
		(fp_line
			(start 0.899922 0.700024)
			(end 0.899922 0.175006)
			(stroke
				(width 0.1)
				(type default)
			)
			(layer "B.Fab")
		)
		(fp_line
			(start 0.299974 0.500126)
			(end -0.199898 0)
			(stroke
				(width 0.1)
				(type default)
			)
			(layer "B.Fab")
		)
		(fp_line
			(start -1.35001 0.175006)
			(end -0.899922 0.175006)
			(stroke
				(width 0.1)
				(type default)
			)
			(layer "B.Fab")
		)
		(fp_line
			(start -0.899922 0.175006)
			(end -0.899922 0.700024)
			(stroke
				(width 0.1)
				(type default)
			)
			(layer "B.Fab")
		)
		(fp_line
			(start 0.899922 0.175006)
			(end 1.35001 0.175006)
			(stroke
				(width 0.1)
				(type default)
			)
			(layer "B.Fab")
		)
		(fp_line
			(start 1.35001 0.175006)
			(end 1.35001 -0.225044)
			(stroke
				(width 0.1)
				(type default)
			)
			(layer "B.Fab")
		)
		(fp_line
			(start -0.199898 0)
			(end 0.299974 -0.500126)
			(stroke
				(width 0.1)
				(type default)
			)
			(layer "B.Fab")
		)
		(fp_line
			(start -1.35001 -0.225044)
			(end -1.35001 0.175006)
			(stroke
				(width 0.1)
				(type default)
			)
			(layer "B.Fab")
		)
		(fp_line
			(start -0.899922 -0.225044)
			(end -1.35001 -0.225044)
			(stroke
				(width 0.1)
				(type default)
			)
			(layer "B.Fab")
		)
		(fp_line
			(start 0.899922 -0.225044)
			(end 0.899922 -0.700024)
			(stroke
				(width 0.1)
				(type default)
			)
			(layer "B.Fab")
		)
		(fp_line
			(start 1.35001 -0.225044)
			(end 0.899922 -0.225044)
			(stroke
				(width 0.1)
				(type default)
			)
			(layer "B.Fab")
		)
		(fp_line
			(start -0.299974 -0.500126)
			(end -0.299974 0.500126)
			(stroke
				(width 0.1)
				(type default)
			)
			(layer "B.Fab")
		)
		(fp_line
			(start 0.299974 -0.500126)
			(end 0.299974 0.500126)
			(stroke
				(width 0.1)
				(type default)
			)
			(layer "B.Fab")
		)
		(fp_line
			(start -0.899922 -0.700024)
			(end -0.899922 -0.225044)
			(stroke
				(width 0.1)
				(type default)
			)
			(layer "B.Fab")
		)
		(fp_line
			(start 0.899922 -0.700024)
			(end -0.899922 -0.700024)
			(stroke
				(width 0.1)
				(type default)
			)
			(layer "B.Fab")
		)
		(fp_text user "-"
			(at -1.8288 -0.24765 270)
			(unlocked yes)
			(layer "B.SilkS")
			(effects
				(font
					(size 1.905 1.4224)
					(thickness 0.1524)
				)
				(justify left mirror)
			)
		)
		(fp_text user "+"
			(at 2.296922 -1.570228 270)
			(unlocked yes)
			(layer "B.SilkS")
			(effects
				(font
					(size 1.905 1.4224)
					(thickness 0.1524)
				)
				(justify left mirror)
			)
		)
		(fp_text user "+"
			(at 2.794 -0.19685 270)
			(unlocked yes)
			(layer "B.Fab")
			(effects
				(font
					(size 1.905 1.4224)
					(thickness 0.1524)
				)
				(justify left mirror)
			)
		)
		(fp_text user "-"
			(at -1.8288 -0.24765 270)
			(unlocked yes)
			(layer "B.Fab")
			(effects
				(font
					(size 1.905 1.4224)
					(thickness 0.1524)
				)
				(justify left mirror)
			)
		)
		(pad "1" smd rect
			(at 1.0922 0 270)
			(size 0.8128 0.8636)
			(layers "B.Cu" "B.Mask" "B.Paste")
			(net "P52V_HS1_4287_GATE_R")
		)
		(pad "2" smd rect
			(at -1.0922 0 90)
			(size 0.8128 0.8636)
			(layers "B.Cu" "B.Mask" "B.Paste")
			(net "P52V_HS1_GATE_R1")
		)
	)
	(footprint ""
		(layer "B.Cu")
		(at 140.850112 -76.708 90)
		(property "Reference" "PR58"
			(at 0 0 90)
			(layer "B.SilkS")
			(hide yes)
			(effects
				(font
					(size 1.27 1.27)
				)
				(justify mirror)
			)
		)
		(property "Value" ""
			(at 0 0 90)
			(layer "B.Fab")
			(effects
				(font
					(size 1.27 1.27)
				)
				(justify mirror)
			)
		)
		(duplicate_pad_numbers_are_jumpers no)
		(fp_line
			(start 0.7874 -0.4064)
			(end -0.7874 -0.4064)
			(stroke
				(width 0.1524)
				(type default)
			)
			(layer "B.SilkS")
		)
		(fp_line
			(start -0.7874 -0.4064)
			(end -0.7874 0.4064)
			(stroke
				(width 0.1524)
				(type default)
			)
			(layer "B.SilkS")
		)
		(fp_line
			(start 0.7874 0.4064)
			(end 0.7874 -0.4064)
			(stroke
				(width 0.1524)
				(type default)
			)
			(layer "B.SilkS")
		)
		(fp_line
			(start -0.7874 0.4064)
			(end 0.7874 0.4064)
			(stroke
				(width 0.1524)
				(type default)
			)
			(layer "B.SilkS")
		)
		(fp_line
			(start 0.67945 -0.305054)
			(end 0.12065 -0.305054)
			(stroke
				(width 0.1)
				(type default)
			)
			(layer "B.Fab")
		)
		(fp_line
			(start 0.12065 -0.305054)
			(end 0.12065 -0.2794)
			(stroke
				(width 0.1)
				(type default)
			)
			(layer "B.Fab")
		)
		(fp_line
			(start -0.12065 -0.3048)
			(end -0.67945 -0.3048)
			(stroke
				(width 0.1)
				(type default)
			)
			(layer "B.Fab")
		)
		(fp_line
			(start -0.67945 -0.3048)
			(end -0.67945 0.3048)
			(stroke
				(width 0.1)
				(type default)
			)
			(layer "B.Fab")
		)
		(fp_line
			(start 0.12065 -0.2794)
			(end -0.12065 -0.2794)
			(stroke
				(width 0.1)
				(type default)
			)
			(layer "B.Fab")
		)
		(fp_line
			(start -0.12065 -0.2794)
			(end -0.12065 -0.3048)
			(stroke
				(width 0.1)
				(type default)
			)
			(layer "B.Fab")
		)
		(fp_line
			(start 0.12065 0.2794)
			(end 0.12065 0.3048)
			(stroke
				(width 0.1)
				(type default)
			)
			(layer "B.Fab")
		)
		(fp_line
			(start -0.120396 0.2794)
			(end 0.12065 0.2794)
			(stroke
				(width 0.1)
				(type default)
			)
			(layer "B.Fab")
		)
		(fp_line
			(start 0.67945 0.3048)
			(end 0.67945 -0.305054)
			(stroke
				(width 0.1)
				(type default)
			)
			(layer "B.Fab")
		)
		(fp_line
			(start 0.12065 0.3048)
			(end 0.67945 0.3048)
			(stroke
				(width 0.1)
				(type default)
			)
			(layer "B.Fab")
		)
		(fp_line
			(start -0.120396 0.3048)
			(end -0.120396 0.2794)
			(stroke
				(width 0.1)
				(type default)
			)
			(layer "B.Fab")
		)
		(fp_line
			(start -0.67945 0.3048)
			(end -0.120396 0.3048)
			(stroke
				(width 0.1)
				(type default)
			)
			(layer "B.Fab")
		)
		(pad "1" smd circle
			(at 0.40005 0 270)
			(size 0 0)
			(layers "B.Cu" "B.Mask" "B.Paste")
			(net "GND")
		)
		(pad "2" smd circle
			(at -0.40005 0 270)
			(size 0 0)
			(layers "B.Cu" "B.Mask" "B.Paste")
			(net "BRICK0_PMBADD")
		)
	)
	(footprint ""
		(layer "B.Cu")
		(at 273.685 -26.543 90)
		(property "Reference" "U37"
			(at -2.32537 1.7399 0)
			(unlocked yes)
			(layer "B.SilkS")
			(effects
				(font
					(size 0.7874 0.5842)
					(thickness 0.1524)
				)
				(justify left mirror)
			)
		)
		(property "Value" ""
			(at 0 0 90)
			(layer "B.Fab")
			(effects
				(font
					(size 1.27 1.27)
				)
				(justify mirror)
			)
		)
		(duplicate_pad_numbers_are_jumpers no)
		(fp_line
			(start 1.603248 -1.500124)
			(end -1.603248 -1.500124)
			(stroke
				(width 0.1524)
				(type default)
			)
			(layer "B.SilkS")
		)
		(fp_line
			(start -1.603248 -1.500124)
			(end -1.603248 1.500124)
			(stroke
				(width 0.1524)
				(type default)
			)
			(layer "B.SilkS")
		)
		(fp_line
			(start 1.603248 1.500124)
			(end 1.603248 -1.500124)
			(stroke
				(width 0.1524)
				(type default)
			)
			(layer "B.SilkS")
		)
		(fp_line
			(start -1.603248 1.500124)
			(end 1.603248 1.500124)
			(stroke
				(width 0.1524)
				(type default)
			)
			(layer "B.SilkS")
		)
		(fp_line
			(start 0.700024 -1.500124)
			(end 0.700024 -1.169924)
			(stroke
				(width 0.1)
				(type default)
			)
			(layer "B.Fab")
		)
		(fp_line
			(start -0.700024 -1.500124)
			(end 0.700024 -1.500124)
			(stroke
				(width 0.1)
				(type default)
			)
			(layer "B.Fab")
		)
		(fp_line
			(start 1.249934 -1.169924)
			(end 1.249934 -0.729996)
			(stroke
				(width 0.1)
				(type default)
			)
			(layer "B.Fab")
		)
		(fp_line
			(start 0.700024 -1.169924)
			(end 1.249934 -1.169924)
			(stroke
				(width 0.1)
				(type default)
			)
			(layer "B.Fab")
		)
		(fp_line
			(start 1.249934 -0.729996)
			(end 0.6985 -0.729996)
			(stroke
				(width 0.1)
				(type default)
			)
			(layer "B.Fab")
		)
		(fp_line
			(start 0.6985 -0.729996)
			(end 0.6985 0.729996)
			(stroke
				(width 0.1)
				(type default)
			)
			(layer "B.Fab")
		)
		(fp_line
			(start -0.700024 -0.219964)
			(end -0.700024 -1.500124)
			(stroke
				(width 0.1)
				(type default)
			)
			(layer "B.Fab")
		)
		(fp_line
			(start -1.249934 -0.219964)
			(end -0.700024 -0.219964)
			(stroke
				(width 0.1)
				(type default)
			)
			(layer "B.Fab")
		)
		(fp_line
			(start -0.700024 0.219964)
			(end -1.249934 0.219964)
			(stroke
				(width 0.1)
				(type default)
			)
			(layer "B.Fab")
		)
		(fp_line
			(start -1.249934 0.219964)
			(end -1.249934 -0.219964)
			(stroke
				(width 0.1)
				(type default)
			)
			(layer "B.Fab")
		)
		(fp_line
			(start 1.249934 0.729996)
			(end 1.249934 1.169924)
			(stroke
				(width 0.1)
				(type default)
			)
			(layer "B.Fab")
		)
		(fp_line
			(start 0.6985 0.729996)
			(end 1.249934 0.729996)
			(stroke
				(width 0.1)
				(type default)
			)
			(layer "B.Fab")
		)
		(fp_line
			(start 1.249934 1.169924)
			(end 0.700024 1.169924)
			(stroke
				(width 0.1)
				(type default)
			)
			(layer "B.Fab")
		)
		(fp_line
			(start 0.700024 1.169924)
			(end 0.700024 1.500124)
			(stroke
				(width 0.1)
				(type default)
			)
			(layer "B.Fab")
		)
		(fp_line
			(start 0.700024 1.500124)
			(end -0.700024 1.500124)
			(stroke
				(width 0.1)
				(type default)
			)
			(layer "B.Fab")
		)
		(fp_line
			(start -0.700024 1.500124)
			(end -0.700024 0.219964)
			(stroke
				(width 0.1)
				(type default)
			)
			(layer "B.Fab")
		)
		(fp_rect
			(start 0.700024 1.500124)
			(end -0.700024 -1.500124)
			(stroke
				(width 0)
				(type default)
			)
			(fill no)
			(layer "B.Fab")
		)
		(pad "D" smd rect
			(at -0.999998 0)
			(size 0.8128 0.9144)
			(layers "B.Cu" "B.Mask" "B.Paste")
			(net "P52V_HS1_EN")
		)
		(pad "G" smd rect
			(at 0.999998 -0.94996)
			(size 0.8128 0.9144)
			(layers "B.Cu" "B.Mask" "B.Paste")
			(net "FM_AC_PWR_CYCLE_R_BUF")
		)
		(pad "S" smd rect
			(at 0.999998 0.94996)
			(size 0.8128 0.9144)
			(layers "B.Cu" "B.Mask" "B.Paste")
			(net "GND")
		)
	)
	(footprint ""
		(layer "B.Cu")
		(at 222.25 -75.057 -90)
		(property "Reference" "R44"
			(at 0 0 90)
			(layer "B.SilkS")
			(hide yes)
			(effects
				(font
					(size 1.27 1.27)
				)
				(justify mirror)
			)
		)
		(property "Value" ""
			(at 0 0 90)
			(layer "B.Fab")
			(effects
				(font
					(size 1.27 1.27)
				)
				(justify mirror)
			)
		)
		(duplicate_pad_numbers_are_jumpers no)
		(fp_line
			(start -0.7874 0.4064)
			(end 0.7874 0.4064)
			(stroke
				(width 0.1524)
				(type default)
			)
			(layer "B.SilkS")
		)
		(fp_line
			(start 0.7874 0.4064)
			(end 0.7874 -0.4064)
			(stroke
				(width 0.1524)
				(type default)
			)
			(layer "B.SilkS")
		)
		(fp_line
			(start -0.7874 -0.4064)
			(end -0.7874 0.4064)
			(stroke
				(width 0.1524)
				(type default)
			)
			(layer "B.SilkS")
		)
		(fp_line
			(start 0.7874 -0.4064)
			(end -0.7874 -0.4064)
			(stroke
				(width 0.1524)
				(type default)
			)
			(layer "B.SilkS")
		)
		(fp_line
			(start -0.67945 0.3048)
			(end -0.120396 0.3048)
			(stroke
				(width 0.1)
				(type default)
			)
			(layer "B.Fab")
		)
		(fp_line
			(start -0.120396 0.3048)
			(end -0.120396 0.2794)
			(stroke
				(width 0.1)
				(type default)
			)
			(layer "B.Fab")
		)
		(fp_line
			(start 0.12065 0.3048)
			(end 0.67945 0.3048)
			(stroke
				(width 0.1)
				(type default)
			)
			(layer "B.Fab")
		)
		(fp_line
			(start 0.67945 0.3048)
			(end 0.67945 -0.305054)
			(stroke
				(width 0.1)
				(type default)
			)
			(layer "B.Fab")
		)
		(fp_line
			(start -0.120396 0.2794)
			(end 0.12065 0.2794)
			(stroke
				(width 0.1)
				(type default)
			)
			(layer "B.Fab")
		)
		(fp_line
			(start 0.12065 0.2794)
			(end 0.12065 0.3048)
			(stroke
				(width 0.1)
				(type default)
			)
			(layer "B.Fab")
		)
		(fp_line
			(start -0.12065 -0.2794)
			(end -0.12065 -0.3048)
			(stroke
				(width 0.1)
				(type default)
			)
			(layer "B.Fab")
		)
		(fp_line
			(start 0.12065 -0.2794)
			(end -0.12065 -0.2794)
			(stroke
				(width 0.1)
				(type default)
			)
			(layer "B.Fab")
		)
		(fp_line
			(start -0.67945 -0.3048)
			(end -0.67945 0.3048)
			(stroke
				(width 0.1)
				(type default)
			)
			(layer "B.Fab")
		)
		(fp_line
			(start -0.12065 -0.3048)
			(end -0.67945 -0.3048)
			(stroke
				(width 0.1)
				(type default)
			)
			(layer "B.Fab")
		)
		(fp_line
			(start 0.12065 -0.305054)
			(end 0.12065 -0.2794)
			(stroke
				(width 0.1)
				(type default)
			)
			(layer "B.Fab")
		)
		(fp_line
			(start 0.67945 -0.305054)
			(end 0.12065 -0.305054)
			(stroke
				(width 0.1)
				(type default)
			)
			(layer "B.Fab")
		)
		(pad "1" smd circle
			(at 0.40005 0 90)
			(size 0 0)
			(layers "B.Cu" "B.Mask" "B.Paste")
			(net "GND")
		)
		(pad "2" smd circle
			(at -0.40005 0 90)
			(size 0 0)
			(layers "B.Cu" "B.Mask" "B.Paste")
			(net "FRU_ADDR1")
		)
	)
	(footprint ""
		(layer "B.Cu")
		(at 96.52 -77.47 180)
		(property "Reference" "C59"
			(at 0 0 0)
			(layer "B.SilkS")
			(hide yes)
			(effects
				(font
					(size 1.27 1.27)
				)
				(justify mirror)
			)
		)
		(property "Value" ""
			(at 0 0 0)
			(layer "B.Fab")
			(effects
				(font
					(size 1.27 1.27)
				)
				(justify mirror)
			)
		)
		(duplicate_pad_numbers_are_jumpers no)
		(fp_line
			(start 0.7874 0.4064)
			(end 0.7874 -0.4064)
			(stroke
				(width 0.1524)
				(type default)
			)
			(layer "B.SilkS")
		)
		(fp_line
			(start 0.7874 -0.4064)
			(end -0.7874 -0.4064)
			(stroke
				(width 0.1524)
				(type default)
			)
			(layer "B.SilkS")
		)
		(fp_line
			(start -0.7874 0.4064)
			(end 0.7874 0.4064)
			(stroke
				(width 0.1524)
				(type default)
			)
			(layer "B.SilkS")
		)
		(fp_line
			(start -0.7874 -0.4064)
			(end -0.7874 0.4064)
			(stroke
				(width 0.1524)
				(type default)
			)
			(layer "B.SilkS")
		)
		(fp_line
			(start 0.67945 0.3048)
			(end 0.67945 -0.305054)
			(stroke
				(width 0.1)
				(type default)
			)
			(layer "B.Fab")
		)
		(fp_line
			(start 0.67945 -0.305054)
			(end 0.12065 -0.305054)
			(stroke
				(width 0.1)
				(type default)
			)
			(layer "B.Fab")
		)
		(fp_line
			(start 0.12065 0.3048)
			(end 0.67945 0.3048)
			(stroke
				(width 0.1)
				(type default)
			)
			(layer "B.Fab")
		)
		(fp_line
			(start 0.12065 0.2794)
			(end 0.12065 0.3048)
			(stroke
				(width 0.1)
				(type default)
			)
			(layer "B.Fab")
		)
		(fp_line
			(start 0.12065 -0.2794)
			(end -0.12065 -0.2794)
			(stroke
				(width 0.1)
				(type default)
			)
			(layer "B.Fab")
		)
		(fp_line
			(start 0.12065 -0.305054)
			(end 0.12065 -0.2794)
			(stroke
				(width 0.1)
				(type default)
			)
			(layer "B.Fab")
		)
		(fp_line
			(start -0.120396 0.3048)
			(end -0.120396 0.2794)
			(stroke
				(width 0.1)
				(type default)
			)
			(layer "B.Fab")
		)
		(fp_line
			(start -0.120396 0.2794)
			(end 0.12065 0.2794)
			(stroke
				(width 0.1)
				(type default)
			)
			(layer "B.Fab")
		)
		(fp_line
			(start -0.12065 -0.2794)
			(end -0.12065 -0.3048)
			(stroke
				(width 0.1)
				(type default)
			)
			(layer "B.Fab")
		)
		(fp_line
			(start -0.12065 -0.3048)
			(end -0.67945 -0.3048)
			(stroke
				(width 0.1)
				(type default)
			)
			(layer "B.Fab")
		)
		(fp_line
			(start -0.67945 0.3048)
			(end -0.120396 0.3048)
			(stroke
				(width 0.1)
				(type default)
			)
			(layer "B.Fab")
		)
		(fp_line
			(start -0.67945 -0.3048)
			(end -0.67945 0.3048)
			(stroke
				(width 0.1)
				(type default)
			)
			(layer "B.Fab")
		)
		(pad "1" smd circle
			(at 0.40005 0)
			(size 0 0)
			(layers "B.Cu" "B.Mask" "B.Paste")
			(net "SMB_P52V_VPDB_SCL")
		)
		(pad "2" smd circle
			(at -0.40005 0)
			(size 0 0)
			(layers "B.Cu" "B.Mask" "B.Paste")
			(net "GND")
		)
	)
)
